FILE_TYPE = MACRO_DRAWING;
SET COLOR_WIRE YELLOW;
SET COLOR_PROP ORANGE;
SET COLOR_DOT WHITE;
SET COLOR_ARC YELLOW;
SET COLOR_BODY GREEN;
SET COLOR_NOTE PURPLE;
SET PROP_DISPLAY VALUE;
SET PAGE_NUMBER P11;
FORCEADD OFFPAGE_OUT..1
R 2
(-8900 5950);
FORCEPROP 2 LAST PATH I1
J 0
(-9050 6000);
DISPLAY 1.021277 (-9050 6000);
DISPLAY INVISIBLE (-9050 6000);
FORCEPROP 1 LAST OFFPAGE TRUE
J 2
(-8910 6005);
DISPLAY 0.808511 (-8910 6005);
PAINT GREEN (-8910 6005);
DISPLAY INVISIBLE (-8910 6005);
FORCEPROP 1 LAST CDS_LMAN_SYM_OUTLINE -50,50,50,-50
J 2
(-8900 5950);
DISPLAY 0.468085 (-8900 5950);
PAINT GREEN (-8900 5950);
DISPLAY INVISIBLE (-8900 5950);
FORCEPROP 2 LAST CDS_LIB cls
J 0
(-8900 5950);
DISPLAY INVISIBLE (-8900 5950);
FORCEPROP 1 LAST BODY_TYPE COMMENT
J 2
(-8910 6085);
DISPLAY 0.808511 (-8910 6085);
PAINT GREEN (-8910 6085);
DISPLAY INVISIBLE (-8910 6085);
FORCEPROP 2 LAST $XR0 11E5< 
J 0
(-9083 5950);
DISPLAY 0.638298 (-9083 5950);
PAINT MONO (-9083 5950);
FORCEADD OFFPAGE_OUT..1
R 2
(-8900 6150);
FORCEPROP 2 LAST PATH I10
J 0
(-9050 6200);
DISPLAY 1.021277 (-9050 6200);
DISPLAY INVISIBLE (-9050 6200);
FORCEPROP 1 LAST OFFPAGE TRUE
J 2
(-8910 6205);
DISPLAY 0.808511 (-8910 6205);
PAINT GREEN (-8910 6205);
DISPLAY INVISIBLE (-8910 6205);
FORCEPROP 2 LAST CDS_LIB cls
J 0
(-8900 6150);
DISPLAY INVISIBLE (-8900 6150);
FORCEPROP 1 LAST CDS_LMAN_SYM_OUTLINE -50,50,50,-50
J 2
(-8900 6150);
DISPLAY 0.468085 (-8900 6150);
PAINT GREEN (-8900 6150);
DISPLAY INVISIBLE (-8900 6150);
FORCEPROP 1 LAST BODY_TYPE COMMENT
J 2
(-8910 6285);
DISPLAY 0.808511 (-8910 6285);
PAINT GREEN (-8910 6285);
DISPLAY INVISIBLE (-8910 6285);
FORCEPROP 2 LAST $XR0 11C13< 
J 0
(-9114 6150);
DISPLAY 0.638298 (-9114 6150);
PAINT MONO (-9114 6150);
FORCEADD RESISTOR..1
(-6300 6150);
FORCEPROP 1 LAST $LOCATION R109
J 2
(-6500 6150);
DISPLAY 1.212766 (-6500 6150);
PAINT GREEN (-6500 6150);
FORCEPROP 0 LAST CDS_LOCATION R109
J 0
(-6100 6250);
DISPLAY 1.021277 (-6100 6250);
DISPLAY INVISIBLE (-6100 6250);
FORCEPROP 0 LAST $SEC 1
J 0
(-6100 6250);
DISPLAY 0.680851 (-6100 6250);
PAINT MONO (-6100 6250);
DISPLAY INVISIBLE (-6100 6250);
FORCEPROP 0 LAST CDS_SEC 1
J 0
(-6100 6250);
DISPLAY 1.021277 (-6100 6250);
DISPLAY INVISIBLE (-6100 6250);
FORCEPROP 0 LASTPIN (-6400 6150) $PN 1
J 2
(-6410 6160);
DISPLAY 0.680851 (-6410 6160);
PAINT MONO (-6410 6160);
FORCEPROP 0 LASTPIN (-6150 6150) $PN 2
J 0
(-6140 6160);
DISPLAY 0.680851 (-6140 6160);
PAINT MONO (-6140 6160);
FORCEPROP 0 LAST PACKAGE 0402
J 0
(-6350 6150);
DISPLAY 0.808511 (-6350 6150);
FORCEPROP 1 LAST VALUE 33OHM
J 0
(-6100 6150);
DISPLAY 1.234043 (-6100 6150);
PAINT GREEN (-6100 6150);
FORCEPROP 1 LAST PATH I11
J 0
(-6497 6255);
DISPLAY 1.212766 (-6497 6255);
PAINT GREEN (-6497 6255);
DISPLAY INVISIBLE (-6497 6255);
FORCEPROP 1 LAST TOLERANCE 1%
J 0
(-6497 6405);
DISPLAY 1.212766 (-6497 6405);
PAINT GREEN (-6497 6405);
DISPLAY INVISIBLE (-6497 6405);
FORCEPROP 1 LAST CLS_PN G155-133R0-01
J 0
(-6436 6350);
DISPLAY 1.212766 (-6436 6350);
PAINT GREEN (-6436 6350);
DISPLAY INVISIBLE (-6436 6350);
FORCEPROP 2 LAST SIGNAL_MODEL DEFAULT_RESISTOR_33OHM_2_1
J 0
(-6450 6350);
DISPLAY 1.021277 (-6450 6350);
DISPLAY INVISIBLE (-6450 6350);
FORCEPROP 1 LAST CDS_LMAN_SYM_OUTLINE -50,50,100,-50
J 0
(-6300 6150);
DISPLAY 0.468085 (-6300 6150);
PAINT GREEN (-6300 6150);
DISPLAY INVISIBLE (-6300 6150);
FORCEPROP 2 LAST CDS_LIB passive
J 0
(-6300 6150);
DISPLAY INVISIBLE (-6300 6150);
FORCEADD CAPACITOR..1
R 5
(-6050 6950);
FORCEPROP 1 LAST $LOCATION C72
J 2
(-5800 6850);
DISPLAY 1.212766 (-5800 6850);
PAINT GREEN (-5800 6850);
FORCEPROP 0 LAST CDS_LOCATION C72
J 0
(-5950 7050);
DISPLAY 1.021277 (-5950 7050);
DISPLAY INVISIBLE (-5950 7050);
FORCEPROP 0 LAST $SEC 1
J 0
(-5950 7050);
DISPLAY 0.680851 (-5950 7050);
PAINT MONO (-5950 7050);
DISPLAY INVISIBLE (-5950 7050);
FORCEPROP 0 LAST CDS_SEC 1
J 0
(-5950 7050);
DISPLAY 1.021277 (-5950 7050);
DISPLAY INVISIBLE (-5950 7050);
FORCEPROP 0 LASTPIN (-6050 7050) $PN 1
R 1
J 0
(-6060 7060);
DISPLAY 0.680851 (-6060 7060);
PAINT MONO (-6060 7060);
FORCEPROP 0 LASTPIN (-6050 6800) $PN 2
R 1
J 2
(-6060 6790);
DISPLAY 0.680851 (-6060 6790);
PAINT MONO (-6060 6790);
FORCEPROP 1 LAST VALUE 10UF
J 0
(-5950 6950);
DISPLAY 1.212766 (-5950 6950);
PAINT GREEN (-5950 6950);
FORCEPROP 0 LAST PACKAGE 0805
J 0
(-5950 7050);
DISPLAY 1.021277 (-5950 7050);
FORCEPROP 0 LAST VOLTAGE 25V
J 0
(-5950 7150);
DISPLAY 1.021277 (-5950 7150);
FORCEPROP 1 LAST PATH I12
R 3
J 2
(-5950 7000);
DISPLAY 1.212766 (-5950 7000);
PAINT GREEN (-5950 7000);
DISPLAY INVISIBLE (-5950 7000);
FORCEPROP 2 LAST CDS_LIB passive
J 0
(-6050 6950);
DISPLAY INVISIBLE (-6050 6950);
FORCEPROP 1 LAST CDS_LMAN_SYM_OUTLINE 0,50,50,-50
R 3
J 0
(-6050 6950);
DISPLAY 0.468085 (-6050 6950);
PAINT GREEN (-6050 6950);
DISPLAY INVISIBLE (-6050 6950);
FORCEPROP 1 LAST CLS_PN G107-0F106-EM
R 3
J 2
(-5950 7000);
DISPLAY 1.212766 (-5950 7000);
PAINT GREEN (-5950 7000);
DISPLAY INVISIBLE (-5950 7000);
FORCEPROP 1 LAST TOLERANCE 20%
R 3
J 2
(-5950 7050);
DISPLAY 1.212766 (-5950 7050);
PAINT GREEN (-5950 7050);
DISPLAY INVISIBLE (-5950 7050);
FORCEADD CAPACITOR..1
R 3
(-5650 6950);
FORCEPROP 1 LAST $LOCATION C73
J 0
(-5550 6850);
DISPLAY 1.212766 (-5550 6850);
PAINT GREEN (-5550 6850);
FORCEPROP 0 LAST CDS_LOCATION C73
R 1
J 0
(-5550 7050);
DISPLAY 1.021277 (-5550 7050);
DISPLAY INVISIBLE (-5550 7050);
FORCEPROP 0 LAST $SEC 1
R 1
J 0
(-5550 7050);
DISPLAY 0.680851 (-5550 7050);
PAINT MONO (-5550 7050);
DISPLAY INVISIBLE (-5550 7050);
FORCEPROP 0 LAST CDS_SEC 1
R 1
J 0
(-5550 7050);
DISPLAY 1.021277 (-5550 7050);
DISPLAY INVISIBLE (-5550 7050);
FORCEPROP 0 LASTPIN (-5650 7050) $PN 1
R 1
J 0
(-5660 7060);
DISPLAY 0.680851 (-5660 7060);
PAINT MONO (-5660 7060);
FORCEPROP 0 LASTPIN (-5650 6800) $PN 2
R 1
J 2
(-5660 6790);
DISPLAY 0.680851 (-5660 6790);
PAINT MONO (-5660 6790);
FORCEPROP 0 LAST VOLTAGE 25V
J 0
(-5550 7150);
DISPLAY 1.021277 (-5550 7150);
FORCEPROP 0 LAST PACKAGE 0402
J 0
(-5550 7050);
DISPLAY 1.021277 (-5550 7050);
FORCEPROP 1 LAST VALUE 0.1UF
J 0
(-5550 6950);
DISPLAY 1.212766 (-5550 6950);
PAINT GREEN (-5550 6950);
FORCEPROP 1 LAST PATH I13
R 1
J 0
(-5750 7000);
DISPLAY 1.212766 (-5750 7000);
PAINT GREEN (-5750 7000);
DISPLAY INVISIBLE (-5750 7000);
FORCEPROP 1 LAST CDS_LMAN_SYM_OUTLINE 0,50,50,-50
R 1
J 2
(-5650 6950);
DISPLAY 0.468085 (-5650 6950);
PAINT GREEN (-5650 6950);
DISPLAY INVISIBLE (-5650 6950);
FORCEPROP 2 LAST CDS_LIB passive
J 0
(-5650 6950);
DISPLAY INVISIBLE (-5650 6950);
FORCEPROP 1 LAST TOLERANCE 10%
R 1
J 0
(-5750 7050);
DISPLAY 1.212766 (-5750 7050);
PAINT GREEN (-5750 7050);
DISPLAY INVISIBLE (-5750 7050);
FORCEPROP 1 LAST CLS_PN G105-0B104-EK
R 1
J 0
(-5750 7000);
DISPLAY 1.212766 (-5750 7000);
PAINT GREEN (-5750 7000);
DISPLAY INVISIBLE (-5750 7000);
FORCEADD GND_SG..1
(-5250 6600);
FORCEPROP 3 LASTPIN (-5200 6650) SIG_NAME SG\g
J 0
(-5190 6660);
DISPLAY 0.659574 (-5190 6660);
PAINT MONO (-5190 6660);
DISPLAY INVISIBLE (-5190 6660);
FORCEPROP 1 LAST HDL_POWER SG
J 1
(-5195 6505);
DISPLAY 0.808511 (-5195 6505);
PAINT GREEN (-5195 6505);
FORCEPROP 1 LAST PATH I14
J 0
(-5215 6600);
DISPLAY 0.808511 (-5215 6600);
PAINT GREEN (-5215 6600);
DISPLAY INVISIBLE (-5215 6600);
FORCEPROP 1 LAST BODY_TYPE PLUMBING
J 0
(-5235 6585);
DISPLAY 0.808511 (-5235 6585);
PAINT GREEN (-5235 6585);
DISPLAY INVISIBLE (-5235 6585);
FORCEPROP 2 LAST CDS_LIB cls
J 0
(-5250 6600);
DISPLAY INVISIBLE (-5250 6600);
FORCEPROP 1 LAST CDS_LMAN_SYM_OUTLINE 0,0,100,-50
J 0
(-5250 6600);
DISPLAY 0.468085 (-5250 6600);
PAINT GREEN (-5250 6600);
DISPLAY INVISIBLE (-5250 6600);
FORCEPROP 0 LAST VOLTAGE 0
J 0
(-5150 6600);
DISPLAY 1.021277 (-5150 6600);
DISPLAY INVISIBLE (-5150 6600);
FORCEADD CAPACITOR..1
R 3
(-5200 6950);
FORCEPROP 1 LAST $LOCATION C78
J 0
(-5100 6850);
DISPLAY 1.212766 (-5100 6850);
PAINT GREEN (-5100 6850);
FORCEPROP 0 LAST CDS_LOCATION C78
R 1
J 0
(-5100 7050);
DISPLAY 1.021277 (-5100 7050);
DISPLAY INVISIBLE (-5100 7050);
FORCEPROP 0 LAST $SEC 1
R 1
J 0
(-5100 7050);
DISPLAY 0.680851 (-5100 7050);
PAINT MONO (-5100 7050);
DISPLAY INVISIBLE (-5100 7050);
FORCEPROP 0 LAST CDS_SEC 1
R 1
J 0
(-5100 7050);
DISPLAY 1.021277 (-5100 7050);
DISPLAY INVISIBLE (-5100 7050);
FORCEPROP 0 LASTPIN (-5200 7050) $PN 1
R 1
J 0
(-5210 7060);
DISPLAY 0.680851 (-5210 7060);
PAINT MONO (-5210 7060);
FORCEPROP 0 LASTPIN (-5200 6800) $PN 2
R 1
J 2
(-5210 6790);
DISPLAY 0.680851 (-5210 6790);
PAINT MONO (-5210 6790);
FORCEPROP 0 LAST VOLTAGE 25V
J 0
(-5100 7150);
DISPLAY 1.021277 (-5100 7150);
FORCEPROP 0 LAST PACKAGE 0402
J 0
(-5100 7050);
DISPLAY 1.021277 (-5100 7050);
FORCEPROP 1 LAST VALUE 0.1UF
J 0
(-5100 6950);
DISPLAY 1.212766 (-5100 6950);
PAINT GREEN (-5100 6950);
FORCEPROP 1 LAST PATH I15
R 1
J 0
(-5300 7000);
DISPLAY 1.212766 (-5300 7000);
PAINT GREEN (-5300 7000);
DISPLAY INVISIBLE (-5300 7000);
FORCEPROP 1 LAST CLS_PN G105-0B104-EK
R 1
J 0
(-5300 7000);
DISPLAY 1.212766 (-5300 7000);
PAINT GREEN (-5300 7000);
DISPLAY INVISIBLE (-5300 7000);
FORCEPROP 1 LAST TOLERANCE 10%
R 1
J 0
(-5300 7050);
DISPLAY 1.212766 (-5300 7050);
PAINT GREEN (-5300 7050);
DISPLAY INVISIBLE (-5300 7050);
FORCEPROP 2 LAST CDS_LIB passive
J 0
(-5200 6950);
DISPLAY INVISIBLE (-5200 6950);
FORCEPROP 1 LAST CDS_LMAN_SYM_OUTLINE 0,50,50,-50
R 1
J 2
(-5200 6950);
DISPLAY 0.468085 (-5200 6950);
PAINT GREEN (-5200 6950);
DISPLAY INVISIBLE (-5200 6950);
FORCEADD VCC..1
(-4800 7400);
FORCEPROP 3 LASTPIN (-4750 7350) SIG_NAME XP5R0V_VCC_ANT\g
J 0
(-4740 7360);
DISPLAY 0.659574 (-4740 7360);
PAINT MONO (-4740 7360);
DISPLAY INVISIBLE (-4740 7360);
FORCEPROP 1 LAST HDL_POWER XP5R0V_VCC_ANT
J 1
(-4750 7450);
DISPLAY 0.808511 (-4750 7450);
PAINT GREEN (-4750 7450);
FORCEPROP 0 LAST VOLTAGE 5
J 1
(-4750 7550);
DISPLAY 1.021277 (-4750 7550);
DISPLAY BOTH (-4750 7550);
FORCEPROP 1 LAST PATH I16
J 0
(-4765 7490);
DISPLAY 0.808511 (-4765 7490);
PAINT GREEN (-4765 7490);
DISPLAY INVISIBLE (-4765 7490);
FORCEPROP 1 LAST BODY_TYPE PLUMBING
J 0
(-4845 7357);
DISPLAY 0.340426 (-4845 7357);
PAINT GREEN (-4845 7357);
DISPLAY INVISIBLE (-4845 7357);
FORCEPROP 2 LAST CDS_LIB cls
J 0
(-4800 7400);
DISPLAY INVISIBLE (-4800 7400);
FORCEPROP 1 LAST CDS_LMAN_SYM_OUTLINE -250,250,250,-250
J 0
(-4800 7400);
DISPLAY 0.468085 (-4800 7400);
PAINT GREEN (-4800 7400);
DISPLAY INVISIBLE (-4800 7400);
FORCEADD GND_SG..1
(-3850 5400);
FORCEPROP 3 LASTPIN (-3800 5450) SIG_NAME SG\g
J 0
(-3790 5460);
DISPLAY 0.659574 (-3790 5460);
PAINT MONO (-3790 5460);
DISPLAY INVISIBLE (-3790 5460);
FORCEPROP 1 LAST HDL_POWER SG
J 1
(-3795 5305);
DISPLAY 0.808511 (-3795 5305);
PAINT GREEN (-3795 5305);
FORCEPROP 1 LAST PATH I17
J 0
(-3815 5400);
DISPLAY 0.808511 (-3815 5400);
PAINT GREEN (-3815 5400);
DISPLAY INVISIBLE (-3815 5400);
FORCEPROP 1 LAST BODY_TYPE PLUMBING
J 0
(-3835 5385);
DISPLAY 0.808511 (-3835 5385);
PAINT GREEN (-3835 5385);
DISPLAY INVISIBLE (-3835 5385);
FORCEPROP 0 LAST VOLTAGE 0
J 0
(-3750 5400);
DISPLAY 1.021277 (-3750 5400);
DISPLAY INVISIBLE (-3750 5400);
FORCEPROP 1 LAST CDS_LMAN_SYM_OUTLINE 0,0,100,-50
J 0
(-3850 5400);
DISPLAY 0.468085 (-3850 5400);
PAINT GREEN (-3850 5400);
DISPLAY INVISIBLE (-3850 5400);
FORCEPROP 2 LAST CDS_LIB cls
J 0
(-3850 5400);
DISPLAY INVISIBLE (-3850 5400);
FORCEADD RESISTOR..2
(-3450 5800);
FORCEPROP 1 LAST $LOCATION R114
J 0
(-3400 5700);
DISPLAY 1.212766 (-3400 5700);
PAINT GREEN (-3400 5700);
FORCEPROP 0 LAST CDS_LOCATION R114
J 0
(-3400 5950);
DISPLAY 1.021277 (-3400 5950);
DISPLAY INVISIBLE (-3400 5950);
FORCEPROP 0 LAST $SEC 1
J 0
(-3400 5950);
DISPLAY 0.680851 (-3400 5950);
PAINT MONO (-3400 5950);
DISPLAY INVISIBLE (-3400 5950);
FORCEPROP 0 LAST CDS_SEC 1
J 0
(-3400 5950);
DISPLAY 1.021277 (-3400 5950);
DISPLAY INVISIBLE (-3400 5950);
FORCEPROP 0 LASTPIN (-3450 5900) $PN 1
R 1
J 0
(-3460 5910);
DISPLAY 0.680851 (-3460 5910);
PAINT MONO (-3460 5910);
FORCEPROP 0 LASTPIN (-3450 5650) $PN 2
R 1
J 2
(-3460 5640);
DISPLAY 0.680851 (-3460 5640);
PAINT MONO (-3460 5640);
FORCEPROP 1 LAST VALUE 4.7KOHM
J 0
(-3400 5800);
DISPLAY 1.212766 (-3400 5800);
PAINT GREEN (-3400 5800);
FORCEPROP 0 LAST PACKAGE 0402
J 0
(-3400 5900);
DISPLAY 1.021277 (-3400 5900);
FORCEPROP 0 LAST NO_ASSY TRUE
J 0
(-3400 5600);
DISPLAY 0.808511 (-3400 5600);
DISPLAY BOTH (-3400 5600);
FORCEPROP 1 LAST PATH I18
J 0
(-3647 5905);
DISPLAY 1.212766 (-3647 5905);
PAINT GREEN (-3647 5905);
DISPLAY INVISIBLE (-3647 5905);
FORCEPROP 1 LAST TOLERANCE 1%
J 0
(-3647 6055);
DISPLAY 1.212766 (-3647 6055);
PAINT GREEN (-3647 6055);
DISPLAY INVISIBLE (-3647 6055);
FORCEPROP 2 LAST CDS_LIB passive
J 0
(-3450 5800);
DISPLAY INVISIBLE (-3450 5800);
FORCEPROP 1 LAST CDS_LMAN_SYM_OUTLINE -50,50,50,-100
J 0
(-3450 5800);
DISPLAY 0.468085 (-3450 5800);
PAINT GREEN (-3450 5800);
DISPLAY INVISIBLE (-3450 5800);
FORCEPROP 1 LAST CLS_PN G155-14701-01
J 0
(-3586 6000);
DISPLAY 1.212766 (-3586 6000);
PAINT GREEN (-3586 6000);
DISPLAY INVISIBLE (-3586 6000);
FORCEADD OFFPAGE_OUT..1
(-350 6050);
FORCEPROP 2 LAST PATH I19
J 0
(-250 6100);
DISPLAY 1.021277 (-250 6100);
DISPLAY INVISIBLE (-250 6100);
FORCEPROP 1 LAST OFFPAGE TRUE
J 0
(-340 6105);
DISPLAY 0.808511 (-340 6105);
PAINT GREEN (-340 6105);
DISPLAY INVISIBLE (-340 6105);
FORCEPROP 2 LAST CDS_LIB cls
J 2
(-350 6050);
DISPLAY INVISIBLE (-350 6050);
FORCEPROP 1 LAST CDS_LMAN_SYM_OUTLINE -50,50,50,-50
J 0
(-350 6050);
DISPLAY 0.468085 (-350 6050);
PAINT GREEN (-350 6050);
DISPLAY INVISIBLE (-350 6050);
FORCEPROP 1 LAST BODY_TYPE COMMENT
J 0
(-340 6185);
DISPLAY 0.808511 (-340 6185);
PAINT GREEN (-340 6185);
DISPLAY INVISIBLE (-340 6185);
FORCEPROP 2 LAST $XR0 11D5< 
J 0
(-295 6050);
DISPLAY 0.638298 (-295 6050);
PAINT MONO (-295 6050);
FORCEADD RESISTOR..1
(-2050 6050);
FORCEPROP 1 LAST $LOCATION R117
J 2
(-2200 6050);
DISPLAY 1.212766 (-2200 6050);
PAINT GREEN (-2200 6050);
FORCEPROP 0 LAST CDS_LOCATION R117
J 0
(-1850 6150);
DISPLAY 1.021277 (-1850 6150);
DISPLAY INVISIBLE (-1850 6150);
FORCEPROP 0 LAST $SEC 1
J 0
(-1850 6150);
DISPLAY 0.680851 (-1850 6150);
PAINT MONO (-1850 6150);
DISPLAY INVISIBLE (-1850 6150);
FORCEPROP 0 LAST CDS_SEC 1
J 0
(-1850 6150);
DISPLAY 1.021277 (-1850 6150);
DISPLAY INVISIBLE (-1850 6150);
FORCEPROP 0 LASTPIN (-2150 6050) $PN 1
J 2
(-2160 6060);
DISPLAY 0.680851 (-2160 6060);
PAINT MONO (-2160 6060);
FORCEPROP 0 LASTPIN (-1900 6050) $PN 2
J 0
(-1890 6060);
DISPLAY 0.680851 (-1890 6060);
PAINT MONO (-1890 6060);
FORCEPROP 1 LAST VALUE 33OHM
J 0
(-1850 6050);
DISPLAY 1.234043 (-1850 6050);
PAINT GREEN (-1850 6050);
FORCEPROP 0 LAST PACKAGE 0402
J 0
(-2100 5950);
DISPLAY 1.021277 (-2100 5950);
FORCEPROP 1 LAST PATH I20
J 0
(-2247 6155);
DISPLAY 1.212766 (-2247 6155);
PAINT GREEN (-2247 6155);
DISPLAY INVISIBLE (-2247 6155);
FORCEPROP 1 LAST TOLERANCE 1%
J 0
(-2247 6305);
DISPLAY 1.212766 (-2247 6305);
PAINT GREEN (-2247 6305);
DISPLAY INVISIBLE (-2247 6305);
FORCEPROP 1 LAST CLS_PN G155-133R0-01
J 0
(-2186 6250);
DISPLAY 1.212766 (-2186 6250);
PAINT GREEN (-2186 6250);
DISPLAY INVISIBLE (-2186 6250);
FORCEPROP 2 LAST CDS_LIB passive
J 0
(-2050 6050);
DISPLAY INVISIBLE (-2050 6050);
FORCEPROP 1 LAST CDS_LMAN_SYM_OUTLINE -50,50,100,-50
J 0
(-2050 6050);
DISPLAY 0.468085 (-2050 6050);
PAINT GREEN (-2050 6050);
DISPLAY INVISIBLE (-2050 6050);
FORCEPROP 2 LAST SIGNAL_MODEL DEFAULT_RESISTOR_33OHM_2_1
J 0
(-2200 6250);
DISPLAY 1.021277 (-2200 6250);
DISPLAY INVISIBLE (-2200 6250);
FORCEADD RESISTOR..2
(-3400 6750);
FORCEPROP 1 LAST $LOCATION R115
J 0
(-3350 6600);
DISPLAY 1.212766 (-3350 6600);
PAINT GREEN (-3350 6600);
FORCEPROP 0 LAST CDS_LOCATION R115
J 0
(-3350 6900);
DISPLAY 1.021277 (-3350 6900);
DISPLAY INVISIBLE (-3350 6900);
FORCEPROP 0 LAST $SEC 1
J 0
(-3350 6900);
DISPLAY 0.680851 (-3350 6900);
PAINT MONO (-3350 6900);
DISPLAY INVISIBLE (-3350 6900);
FORCEPROP 0 LAST CDS_SEC 1
J 0
(-3350 6900);
DISPLAY 1.021277 (-3350 6900);
DISPLAY INVISIBLE (-3350 6900);
FORCEPROP 0 LASTPIN (-3400 6850) $PN 1
R 1
J 0
(-3410 6860);
DISPLAY 0.680851 (-3410 6860);
PAINT MONO (-3410 6860);
FORCEPROP 0 LASTPIN (-3400 6600) $PN 2
R 1
J 2
(-3410 6590);
DISPLAY 0.680851 (-3410 6590);
PAINT MONO (-3410 6590);
FORCEPROP 1 LAST VALUE 4.7KOHM
J 0
(-3350 6800);
DISPLAY 1.212766 (-3350 6800);
PAINT GREEN (-3350 6800);
FORCEPROP 0 LAST PACKAGE 0402
J 0
(-3350 6950);
DISPLAY 1.021277 (-3350 6950);
FORCEPROP 1 LAST PATH I21
J 0
(-3597 6855);
DISPLAY 1.212766 (-3597 6855);
PAINT GREEN (-3597 6855);
DISPLAY INVISIBLE (-3597 6855);
FORCEPROP 1 LAST TOLERANCE 1%
J 0
(-3597 7005);
DISPLAY 1.212766 (-3597 7005);
PAINT GREEN (-3597 7005);
DISPLAY INVISIBLE (-3597 7005);
FORCEPROP 2 LAST CDS_LIB passive
J 0
(-3400 6750);
DISPLAY INVISIBLE (-3400 6750);
FORCEPROP 1 LAST CDS_LMAN_SYM_OUTLINE -50,50,50,-100
J 0
(-3400 6750);
DISPLAY 0.468085 (-3400 6750);
PAINT GREEN (-3400 6750);
DISPLAY INVISIBLE (-3400 6750);
FORCEPROP 1 LAST CLS_PN G155-14701-01
J 0
(-3536 6950);
DISPLAY 1.212766 (-3536 6950);
PAINT GREEN (-3536 6950);
DISPLAY INVISIBLE (-3536 6950);
FORCEADD GND_SG..1
(-2650 6450);
FORCEPROP 3 LASTPIN (-2600 6500) SIG_NAME SG\g
J 0
(-2590 6510);
DISPLAY 0.659574 (-2590 6510);
PAINT MONO (-2590 6510);
DISPLAY INVISIBLE (-2590 6510);
FORCEPROP 1 LAST HDL_POWER SG
J 1
(-2595 6355);
DISPLAY 0.808511 (-2595 6355);
PAINT GREEN (-2595 6355);
FORCEPROP 0 LAST VOLTAGE 0
J 0
(-2550 6450);
DISPLAY 1.021277 (-2550 6450);
DISPLAY INVISIBLE (-2550 6450);
FORCEPROP 2 LAST CDS_LIB cls
J 0
(-2650 6450);
DISPLAY INVISIBLE (-2650 6450);
FORCEPROP 1 LAST CDS_LMAN_SYM_OUTLINE 0,0,100,-50
J 0
(-2650 6450);
DISPLAY 0.468085 (-2650 6450);
PAINT GREEN (-2650 6450);
DISPLAY INVISIBLE (-2650 6450);
FORCEPROP 1 LAST BODY_TYPE PLUMBING
J 0
(-2635 6435);
DISPLAY 0.808511 (-2635 6435);
PAINT GREEN (-2635 6435);
DISPLAY INVISIBLE (-2635 6435);
FORCEPROP 1 LAST PATH I22
J 0
(-2615 6450);
DISPLAY 0.808511 (-2615 6450);
PAINT GREEN (-2615 6450);
DISPLAY INVISIBLE (-2615 6450);
FORCEADD CAPACITOR..1
R 5
(-1600 6850);
FORCEPROP 1 LAST $LOCATION C79
J 2
(-1350 6750);
DISPLAY 1.212766 (-1350 6750);
PAINT GREEN (-1350 6750);
FORCEPROP 0 LAST CDS_LOCATION C79
J 0
(-1500 6950);
DISPLAY 1.021277 (-1500 6950);
DISPLAY INVISIBLE (-1500 6950);
FORCEPROP 0 LAST $SEC 1
J 0
(-1500 6950);
DISPLAY 0.680851 (-1500 6950);
PAINT MONO (-1500 6950);
DISPLAY INVISIBLE (-1500 6950);
FORCEPROP 0 LAST CDS_SEC 1
J 0
(-1500 6950);
DISPLAY 1.021277 (-1500 6950);
DISPLAY INVISIBLE (-1500 6950);
FORCEPROP 0 LASTPIN (-1600 6950) $PN 1
R 1
J 0
(-1610 6960);
DISPLAY 0.680851 (-1610 6960);
PAINT MONO (-1610 6960);
FORCEPROP 0 LASTPIN (-1600 6700) $PN 2
R 1
J 2
(-1610 6690);
DISPLAY 0.680851 (-1610 6690);
PAINT MONO (-1610 6690);
FORCEPROP 0 LAST PACKAGE 0805
J 0
(-1500 7000);
DISPLAY 1.021277 (-1500 7000);
FORCEPROP 0 LAST VOLTAGE 25V
J 0
(-1500 6950);
DISPLAY 1.021277 (-1500 6950);
FORCEPROP 1 LAST VALUE 10UF
J 0
(-1500 6850);
DISPLAY 1.212766 (-1500 6850);
PAINT GREEN (-1500 6850);
FORCEPROP 1 LAST TOLERANCE 20%
R 3
J 2
(-1500 6950);
DISPLAY 1.212766 (-1500 6950);
PAINT GREEN (-1500 6950);
DISPLAY INVISIBLE (-1500 6950);
FORCEPROP 2 LAST CDS_LIB passive
J 0
(-1600 6850);
DISPLAY INVISIBLE (-1600 6850);
FORCEPROP 1 LAST CDS_LMAN_SYM_OUTLINE 0,50,50,-50
R 3
J 0
(-1600 6850);
DISPLAY 0.468085 (-1600 6850);
PAINT GREEN (-1600 6850);
DISPLAY INVISIBLE (-1600 6850);
FORCEPROP 1 LAST CLS_PN G107-0F106-EM
R 3
J 2
(-1500 6900);
DISPLAY 1.212766 (-1500 6900);
PAINT GREEN (-1500 6900);
DISPLAY INVISIBLE (-1500 6900);
FORCEPROP 1 LAST PATH I24
R 3
J 2
(-1500 6900);
DISPLAY 1.212766 (-1500 6900);
PAINT GREEN (-1500 6900);
DISPLAY INVISIBLE (-1500 6900);
FORCEADD RESISTOR..1
(-2050 6150);
FORCEPROP 1 LAST $LOCATION R116
J 2
(-2200 6150);
DISPLAY 1.212766 (-2200 6150);
PAINT GREEN (-2200 6150);
FORCEPROP 0 LAST CDS_LOCATION R116
J 0
(-1850 6250);
DISPLAY 1.021277 (-1850 6250);
DISPLAY INVISIBLE (-1850 6250);
FORCEPROP 0 LAST $SEC 1
J 0
(-1850 6250);
DISPLAY 0.680851 (-1850 6250);
PAINT MONO (-1850 6250);
DISPLAY INVISIBLE (-1850 6250);
FORCEPROP 0 LAST CDS_SEC 1
J 0
(-1850 6250);
DISPLAY 1.021277 (-1850 6250);
DISPLAY INVISIBLE (-1850 6250);
FORCEPROP 0 LASTPIN (-2150 6150) $PN 1
J 2
(-2160 6160);
DISPLAY 0.680851 (-2160 6160);
PAINT MONO (-2160 6160);
FORCEPROP 0 LASTPIN (-1900 6150) $PN 2
J 0
(-1890 6160);
DISPLAY 0.680851 (-1890 6160);
PAINT MONO (-1890 6160);
FORCEPROP 0 LAST PACKAGE 0402
J 0
(-2100 6200);
DISPLAY 1.021277 (-2100 6200);
FORCEPROP 1 LAST VALUE 33OHM
J 0
(-1850 6150);
DISPLAY 1.234043 (-1850 6150);
PAINT GREEN (-1850 6150);
FORCEPROP 1 LAST PATH I25
J 0
(-2247 6255);
DISPLAY 1.212766 (-2247 6255);
PAINT GREEN (-2247 6255);
DISPLAY INVISIBLE (-2247 6255);
FORCEPROP 1 LAST TOLERANCE 1%
J 0
(-2247 6405);
DISPLAY 1.212766 (-2247 6405);
PAINT GREEN (-2247 6405);
DISPLAY INVISIBLE (-2247 6405);
FORCEPROP 1 LAST CLS_PN G155-133R0-01
J 0
(-2186 6350);
DISPLAY 1.212766 (-2186 6350);
PAINT GREEN (-2186 6350);
DISPLAY INVISIBLE (-2186 6350);
FORCEPROP 2 LAST SIGNAL_MODEL DEFAULT_RESISTOR_33OHM_2_1
J 0
(-2200 6350);
DISPLAY 1.021277 (-2200 6350);
DISPLAY INVISIBLE (-2200 6350);
FORCEPROP 1 LAST CDS_LMAN_SYM_OUTLINE -50,50,100,-50
J 0
(-2050 6150);
DISPLAY 0.468085 (-2050 6150);
PAINT GREEN (-2050 6150);
DISPLAY INVISIBLE (-2050 6150);
FORCEPROP 2 LAST CDS_LIB passive
J 0
(-2050 6150);
DISPLAY INVISIBLE (-2050 6150);
FORCEADD CAPACITOR..1
R 3
(-2150 6850);
FORCEPROP 1 LAST $LOCATION C80
J 0
(-2050 6750);
DISPLAY 1.212766 (-2050 6750);
PAINT GREEN (-2050 6750);
FORCEPROP 0 LAST CDS_LOCATION C80
R 1
J 0
(-2050 6950);
DISPLAY 1.021277 (-2050 6950);
DISPLAY INVISIBLE (-2050 6950);
FORCEPROP 0 LAST $SEC 1
R 1
J 0
(-2050 6950);
DISPLAY 0.680851 (-2050 6950);
PAINT MONO (-2050 6950);
DISPLAY INVISIBLE (-2050 6950);
FORCEPROP 0 LAST CDS_SEC 1
R 1
J 0
(-2050 6950);
DISPLAY 1.021277 (-2050 6950);
DISPLAY INVISIBLE (-2050 6950);
FORCEPROP 0 LASTPIN (-2150 6950) $PN 1
R 1
J 0
(-2160 6960);
DISPLAY 0.680851 (-2160 6960);
PAINT MONO (-2160 6960);
FORCEPROP 0 LASTPIN (-2150 6700) $PN 2
R 1
J 2
(-2160 6690);
DISPLAY 0.680851 (-2160 6690);
PAINT MONO (-2160 6690);
FORCEPROP 0 LAST PACKAGE 0402
J 0
(-2050 7000);
DISPLAY 1.021277 (-2050 7000);
FORCEPROP 0 LAST VOLTAGE 10V
J 0
(-2050 6950);
DISPLAY 1.021277 (-2050 6950);
FORCEPROP 1 LAST VALUE 0.1UF
J 0
(-2050 6850);
DISPLAY 1.212766 (-2050 6850);
PAINT GREEN (-2050 6850);
FORCEPROP 1 LAST TOLERANCE 10%
R 1
J 0
(-2250 6950);
DISPLAY 1.212766 (-2250 6950);
PAINT GREEN (-2250 6950);
DISPLAY INVISIBLE (-2250 6950);
FORCEPROP 1 LAST CLS_PN G105-0B104-CK
R 1
J 0
(-2250 6900);
DISPLAY 1.212766 (-2250 6900);
PAINT GREEN (-2250 6900);
DISPLAY INVISIBLE (-2250 6900);
FORCEPROP 2 LAST CDS_LIB passive
J 0
(-2150 6850);
DISPLAY INVISIBLE (-2150 6850);
FORCEPROP 1 LAST CDS_LMAN_SYM_OUTLINE 0,50,50,-50
R 1
J 2
(-2150 6850);
DISPLAY 0.468085 (-2150 6850);
PAINT GREEN (-2150 6850);
DISPLAY INVISIBLE (-2150 6850);
FORCEPROP 1 LAST PATH I26
R 1
J 0
(-2250 6900);
DISPLAY 1.212766 (-2250 6900);
PAINT GREEN (-2250 6900);
DISPLAY INVISIBLE (-2250 6900);
FORCEADD OFFPAGE_IN..2
(-350 6150);
FORCEPROP 1 LAST CDS_LMAN_SYM_OUTLINE -50,50,50,-50
J 0
(-350 6150);
DISPLAY 0.468085 (-350 6150);
PAINT GREEN (-350 6150);
DISPLAY INVISIBLE (-350 6150);
FORCEPROP 2 LAST CDS_LIB cls
J 0
(-350 6150);
DISPLAY INVISIBLE (-350 6150);
FORCEPROP 2 LAST PATH I28
J 0
(-250 6200);
DISPLAY 1.021277 (-250 6200);
DISPLAY INVISIBLE (-250 6200);
FORCEPROP 1 LAST BODY_TYPE COMMENT
J 0
(-340 6285);
DISPLAY 0.808511 (-340 6285);
PAINT GREEN (-340 6285);
DISPLAY INVISIBLE (-340 6285);
FORCEPROP 1 LAST OFFPAGE TRUE
J 0
(-340 6205);
DISPLAY 0.808511 (-340 6205);
PAINT GREEN (-340 6205);
DISPLAY INVISIBLE (-340 6205);
FORCEPROP 2 LAST $XR0 11C5> 
J 0
(-295 6150);
DISPLAY 0.638298 (-295 6150);
PAINT MONO (-295 6150);
FORCEADD RESISTOR..1
(-6300 6050);
FORCEPROP 1 LAST $LOCATION R110
J 2
(-6500 6050);
DISPLAY 1.212766 (-6500 6050);
PAINT GREEN (-6500 6050);
FORCEPROP 0 LAST CDS_LOCATION R110
J 0
(-6100 6150);
DISPLAY 1.021277 (-6100 6150);
DISPLAY INVISIBLE (-6100 6150);
FORCEPROP 0 LAST $SEC 1
J 0
(-6100 6150);
DISPLAY 0.680851 (-6100 6150);
PAINT MONO (-6100 6150);
DISPLAY INVISIBLE (-6100 6150);
FORCEPROP 0 LAST CDS_SEC 1
J 0
(-6100 6150);
DISPLAY 1.021277 (-6100 6150);
DISPLAY INVISIBLE (-6100 6150);
FORCEPROP 0 LASTPIN (-6400 6050) $PN 1
J 2
(-6410 6060);
DISPLAY 0.680851 (-6410 6060);
PAINT MONO (-6410 6060);
FORCEPROP 0 LASTPIN (-6150 6050) $PN 2
J 0
(-6140 6060);
DISPLAY 0.680851 (-6140 6060);
PAINT MONO (-6140 6060);
FORCEPROP 0 LAST PACKAGE 0402
J 0
(-6350 6050);
DISPLAY 0.808511 (-6350 6050);
FORCEPROP 1 LAST VALUE 33OHM
J 0
(-6100 6050);
DISPLAY 1.234043 (-6100 6050);
PAINT GREEN (-6100 6050);
FORCEPROP 1 LAST PATH I29
J 0
(-6497 6155);
DISPLAY 1.212766 (-6497 6155);
PAINT GREEN (-6497 6155);
DISPLAY INVISIBLE (-6497 6155);
FORCEPROP 1 LAST TOLERANCE 1%
J 0
(-6497 6305);
DISPLAY 1.212766 (-6497 6305);
PAINT GREEN (-6497 6305);
DISPLAY INVISIBLE (-6497 6305);
FORCEPROP 1 LAST CLS_PN G155-133R0-01
J 0
(-6436 6250);
DISPLAY 1.212766 (-6436 6250);
PAINT GREEN (-6436 6250);
DISPLAY INVISIBLE (-6436 6250);
FORCEPROP 2 LAST CDS_LIB passive
J 0
(-6300 6050);
DISPLAY INVISIBLE (-6300 6050);
FORCEPROP 1 LAST CDS_LMAN_SYM_OUTLINE -50,50,100,-50
J 0
(-6300 6050);
DISPLAY 0.468085 (-6300 6050);
PAINT GREEN (-6300 6050);
DISPLAY INVISIBLE (-6300 6050);
FORCEPROP 2 LAST SIGNAL_MODEL DEFAULT_RESISTOR_33OHM_2_1
J 0
(-6450 6250);
DISPLAY 1.021277 (-6450 6250);
DISPLAY INVISIBLE (-6450 6250);
FORCEADD VCC..1
(-7100 7400);
FORCEPROP 3 LASTPIN (-7050 7350) SIG_NAME XP5R0V\g
J 0
(-7040 7360);
DISPLAY 0.659574 (-7040 7360);
PAINT MONO (-7040 7360);
DISPLAY INVISIBLE (-7040 7360);
FORCEPROP 0 LAST VOLTAGE 5.0
J 0
(-7300 7500);
DISPLAY 1.021277 (-7300 7500);
DISPLAY BOTH (-7300 7500);
FORCEPROP 1 LAST HDL_POWER XP5R0V
J 1
(-7050 7450);
DISPLAY 1.021277 (-7050 7450);
PAINT GREEN (-7050 7450);
FORCEPROP 1 LAST PATH I32
J 0
(-7065 7490);
DISPLAY 0.808511 (-7065 7490);
PAINT GREEN (-7065 7490);
DISPLAY INVISIBLE (-7065 7490);
FORCEPROP 1 LAST BODY_TYPE PLUMBING
J 0
(-7145 7357);
DISPLAY 0.340426 (-7145 7357);
PAINT GREEN (-7145 7357);
DISPLAY INVISIBLE (-7145 7357);
FORCEPROP 2 LAST CDS_LIB cls
J 0
(-7100 7400);
DISPLAY INVISIBLE (-7100 7400);
FORCEPROP 1 LAST CDS_LMAN_SYM_OUTLINE -250,250,250,-250
J 0
(-7100 7400);
DISPLAY 0.468085 (-7100 7400);
PAINT GREEN (-7100 7400);
DISPLAY INVISIBLE (-7100 7400);
FORCEADD CONN_HDR_2X4_F_S_SMT..1
R 2
(-4150 6350);
FORCEPROP 1 LAST LOCATION P2
J 2
(-4100 5700);
DISPLAY 1.212766 (-4100 5700);
PAINT GREEN (-4100 5700);
FORCEPROP 0 LAST $SEC 1
J 0
(-4100 5800);
DISPLAY 0.680851 (-4100 5800);
PAINT MONO (-4100 5800);
DISPLAY INVISIBLE (-4100 5800);
FORCEPROP 0 LAST CDS_SEC 1
J 0
(-4100 5800);
DISPLAY 1.021277 (-4100 5800);
DISPLAY INVISIBLE (-4100 5800);
FORCEPROP 0 LASTPIN (-4550 6250) $PN 1
J 2
(-4560 6260);
DISPLAY 0.680851 (-4560 6260);
PAINT MONO (-4560 6260);
FORCEPROP 0 LASTPIN (-4050 6250) $PN 2
J 0
(-4040 6260);
DISPLAY 0.680851 (-4040 6260);
PAINT MONO (-4040 6260);
FORCEPROP 0 LASTPIN (-4550 6150) $PN 3
J 2
(-4560 6160);
DISPLAY 0.680851 (-4560 6160);
PAINT MONO (-4560 6160);
FORCEPROP 0 LASTPIN (-4050 6150) $PN 4
J 0
(-4040 6160);
DISPLAY 0.680851 (-4040 6160);
PAINT MONO (-4040 6160);
FORCEPROP 0 LASTPIN (-4550 6050) $PN 5
J 2
(-4560 6060);
DISPLAY 0.680851 (-4560 6060);
PAINT MONO (-4560 6060);
FORCEPROP 0 LASTPIN (-4050 6050) $PN 6
J 0
(-4040 6060);
DISPLAY 0.680851 (-4040 6060);
PAINT MONO (-4040 6060);
FORCEPROP 0 LASTPIN (-4550 5950) $PN 7
J 2
(-4560 5960);
DISPLAY 0.680851 (-4560 5960);
PAINT MONO (-4560 5960);
FORCEPROP 0 LASTPIN (-4050 5950) $PN 8
J 0
(-4040 5960);
DISPLAY 0.680851 (-4040 5960);
PAINT MONO (-4040 5960);
FORCEPROP 0 LAST VALUE SQW-104-01-F-D-VS-K-TR
J 0
(-5150 5500);
FORCEPROP 1 LAST CLS_PN G200-13079-01
J 2
(-4100 5600);
DISPLAY 1.212766 (-4100 5600);
PAINT GREEN (-4100 5600);
FORCEPROP 1 LAST CDS_LMAN_SYM_OUTLINE 0,0,300,-500
J 2
(-4150 6350);
DISPLAY 0.468085 (-4150 6350);
PAINT GREEN (-4150 6350);
DISPLAY INVISIBLE (-4150 6350);
FORCEPROP 2 LAST CDS_LIB connector
J 2
(-4150 6350);
DISPLAY INVISIBLE (-4150 6350);
FORCEPROP 1 LAST PATH I36
J 2
(-4200 6400);
DISPLAY 1.212766 (-4200 6400);
PAINT GREEN (-4200 6400);
DISPLAY INVISIBLE (-4200 6400);
FORCEADD RESISTOR..2
R 1
(-7350 6400);
FORCEPROP 1 LAST $LOCATION R268
J 0
(-7700 6400);
DISPLAY 1.212766 (-7700 6400);
PAINT GREEN (-7700 6400);
FORCEPROP 0 LAST CDS_LOCATION R268
R 1
J 0
(-7150 6500);
DISPLAY 1.021277 (-7150 6500);
DISPLAY INVISIBLE (-7150 6500);
FORCEPROP 0 LAST $SEC 1
R 1
J 0
(-7150 6500);
DISPLAY 0.680851 (-7150 6500);
PAINT MONO (-7150 6500);
DISPLAY INVISIBLE (-7150 6500);
FORCEPROP 0 LAST CDS_SEC 1
R 1
J 0
(-7150 6500);
DISPLAY 1.021277 (-7150 6500);
DISPLAY INVISIBLE (-7150 6500);
FORCEPROP 0 LASTPIN (-7450 6400) $PN 1
J 2
(-7460 6410);
DISPLAY 0.680851 (-7460 6410);
PAINT MONO (-7460 6410);
FORCEPROP 0 LASTPIN (-7200 6400) $PN 2
J 0
(-7190 6410);
DISPLAY 0.680851 (-7190 6410);
PAINT MONO (-7190 6410);
FORCEPROP 0 LAST PACKAGE 0402
J 0
(-7400 6450);
DISPLAY 1.021277 (-7400 6450);
FORCEPROP 1 LAST VALUE 100KOHM
J 0
(-7150 6400);
DISPLAY 1.212766 (-7150 6400);
PAINT GREEN (-7150 6400);
FORCEPROP 1 LAST CLS_PN G155-11003-01
R 1
J 0
(-7550 6264);
DISPLAY 1.212766 (-7550 6264);
PAINT GREEN (-7550 6264);
DISPLAY INVISIBLE (-7550 6264);
FORCEPROP 2 LAST CDS_LIB passive
R 1
J 0
(-7350 6400);
DISPLAY INVISIBLE (-7350 6400);
FORCEPROP 1 LAST CDS_LMAN_SYM_OUTLINE -50,50,50,-100
R 1
J 0
(-7350 6400);
DISPLAY 0.468085 (-7350 6400);
PAINT GREEN (-7350 6400);
DISPLAY INVISIBLE (-7350 6400);
FORCEPROP 1 LAST TOLERANCE 1%
R 1
J 0
(-7605 6203);
DISPLAY 1.212766 (-7605 6203);
PAINT GREEN (-7605 6203);
DISPLAY INVISIBLE (-7605 6203);
FORCEPROP 1 LAST PATH I38
R 1
J 0
(-7455 6203);
DISPLAY 1.212766 (-7455 6203);
PAINT GREEN (-7455 6203);
DISPLAY INVISIBLE (-7455 6203);
FORCEADD VCC..1
(-7900 6600);
FORCEPROP 3 LASTPIN (-7850 6550) SIG_NAME XP3R3V_FPGA\g
J 0
(-7840 6560);
DISPLAY 0.659574 (-7840 6560);
PAINT MONO (-7840 6560);
DISPLAY INVISIBLE (-7840 6560);
FORCEPROP 0 LAST VOLTAGE 3.3V
J 0
(-8100 6750);
DISPLAY 1.021277 (-8100 6750);
DISPLAY BOTH (-8100 6750);
FORCEPROP 1 LAST HDL_POWER XP3R3V_FPGA
J 1
(-7795 6655);
DISPLAY 1.021277 (-7795 6655);
PAINT GREEN (-7795 6655);
FORCEPROP 2 LAST CDS_LIB cls
J 0
(-7900 6600);
DISPLAY INVISIBLE (-7900 6600);
FORCEPROP 1 LAST CDS_LMAN_SYM_OUTLINE -250,250,250,-250
J 0
(-7900 6600);
DISPLAY 0.468085 (-7900 6600);
PAINT GREEN (-7900 6600);
DISPLAY INVISIBLE (-7900 6600);
FORCEPROP 1 LAST BODY_TYPE PLUMBING
J 0
(-7945 6557);
DISPLAY 0.340426 (-7945 6557);
PAINT GREEN (-7945 6557);
DISPLAY INVISIBLE (-7945 6557);
FORCEPROP 1 LAST PATH I39
J 0
(-7865 6690);
DISPLAY 0.808511 (-7865 6690);
PAINT GREEN (-7865 6690);
DISPLAY INVISIBLE (-7865 6690);
FORCEADD RESISTOR..2
R 1
(-7350 6300);
FORCEPROP 1 LAST $LOCATION R269
J 0
(-7700 6300);
DISPLAY 1.212766 (-7700 6300);
PAINT GREEN (-7700 6300);
FORCEPROP 0 LAST CDS_LOCATION R269
R 1
J 0
(-7150 6400);
DISPLAY 1.021277 (-7150 6400);
DISPLAY INVISIBLE (-7150 6400);
FORCEPROP 0 LAST $SEC 1
R 1
J 0
(-7150 6400);
DISPLAY 0.680851 (-7150 6400);
PAINT MONO (-7150 6400);
DISPLAY INVISIBLE (-7150 6400);
FORCEPROP 0 LAST CDS_SEC 1
R 1
J 0
(-7150 6400);
DISPLAY 1.021277 (-7150 6400);
DISPLAY INVISIBLE (-7150 6400);
FORCEPROP 0 LASTPIN (-7450 6300) $PN 1
J 2
(-7460 6310);
DISPLAY 0.680851 (-7460 6310);
PAINT MONO (-7460 6310);
FORCEPROP 0 LASTPIN (-7200 6300) $PN 2
J 0
(-7190 6310);
DISPLAY 0.680851 (-7190 6310);
PAINT MONO (-7190 6310);
FORCEPROP 1 LAST VALUE 100KOHM
J 0
(-7150 6300);
DISPLAY 1.212766 (-7150 6300);
PAINT GREEN (-7150 6300);
FORCEPROP 0 LAST PACKAGE 0402
J 0
(-7400 6200);
DISPLAY 1.021277 (-7400 6200);
FORCEPROP 1 LAST CLS_PN G155-11003-01
R 1
J 0
(-7550 6164);
DISPLAY 1.212766 (-7550 6164);
PAINT GREEN (-7550 6164);
DISPLAY INVISIBLE (-7550 6164);
FORCEPROP 1 LAST CDS_LMAN_SYM_OUTLINE -50,50,50,-100
R 1
J 0
(-7350 6300);
DISPLAY 0.468085 (-7350 6300);
PAINT GREEN (-7350 6300);
DISPLAY INVISIBLE (-7350 6300);
FORCEPROP 2 LAST CDS_LIB passive
R 1
J 0
(-7350 6300);
DISPLAY INVISIBLE (-7350 6300);
FORCEPROP 1 LAST TOLERANCE 1%
R 1
J 0
(-7605 6103);
DISPLAY 1.212766 (-7605 6103);
PAINT GREEN (-7605 6103);
DISPLAY INVISIBLE (-7605 6103);
FORCEPROP 1 LAST PATH I40
R 1
J 0
(-7455 6103);
DISPLAY 1.212766 (-7455 6103);
PAINT GREEN (-7455 6103);
DISPLAY INVISIBLE (-7455 6103);
FORCEADD VCC..1
(-500 7350);
FORCEPROP 3 LASTPIN (-450 7300) SIG_NAME XP3R3V_FPGA\g
J 0
(-440 7310);
DISPLAY 0.659574 (-440 7310);
PAINT MONO (-440 7310);
DISPLAY INVISIBLE (-440 7310);
FORCEPROP 0 LAST VOLTAGE 3.3V
J 0
(-750 7500);
DISPLAY 1.021277 (-750 7500);
DISPLAY BOTH (-750 7500);
FORCEPROP 1 LAST HDL_POWER XP3R3V_FPGA
J 1
(-445 7405);
DISPLAY 1.021277 (-445 7405);
PAINT GREEN (-445 7405);
FORCEPROP 1 LAST CDS_LMAN_SYM_OUTLINE -250,250,250,-250
J 0
(-500 7350);
DISPLAY 0.468085 (-500 7350);
PAINT GREEN (-500 7350);
DISPLAY INVISIBLE (-500 7350);
FORCEPROP 2 LAST CDS_LIB cls
J 0
(-500 7350);
DISPLAY INVISIBLE (-500 7350);
FORCEPROP 1 LAST PATH I42
J 0
(-465 7440);
DISPLAY 0.808511 (-465 7440);
PAINT GREEN (-465 7440);
DISPLAY INVISIBLE (-465 7440);
FORCEPROP 1 LAST BODY_TYPE PLUMBING
J 0
(-545 7307);
DISPLAY 0.340426 (-545 7307);
PAINT GREEN (-545 7307);
DISPLAY INVISIBLE (-545 7307);
FORCEADD CAPACITOR..1
R 3
(-800 6900);
FORCEPROP 1 LAST $LOCATION C81
J 0
(-700 6750);
DISPLAY 1.212766 (-700 6750);
PAINT GREEN (-700 6750);
FORCEPROP 0 LAST CDS_LOCATION C81
R 1
J 0
(-700 7000);
DISPLAY 1.021277 (-700 7000);
DISPLAY INVISIBLE (-700 7000);
FORCEPROP 0 LAST $SEC 1
R 1
J 0
(-700 7000);
DISPLAY 0.680851 (-700 7000);
PAINT MONO (-700 7000);
DISPLAY INVISIBLE (-700 7000);
FORCEPROP 0 LAST CDS_SEC 1
R 1
J 0
(-700 7000);
DISPLAY 1.021277 (-700 7000);
DISPLAY INVISIBLE (-700 7000);
FORCEPROP 0 LASTPIN (-800 7000) $PN 1
R 1
J 0
(-810 7010);
DISPLAY 0.680851 (-810 7010);
PAINT MONO (-810 7010);
FORCEPROP 0 LASTPIN (-800 6750) $PN 2
R 1
J 2
(-810 6740);
DISPLAY 0.680851 (-810 6740);
PAINT MONO (-810 6740);
FORCEPROP 1 LAST VALUE 0.1UF
J 0
(-700 6850);
DISPLAY 1.212766 (-700 6850);
PAINT GREEN (-700 6850);
FORCEPROP 0 LAST VOLTAGE 10V
J 0
(-700 7050);
DISPLAY 1.021277 (-700 7050);
FORCEPROP 0 LAST PACKAGE 0402
J 0
(-700 6950);
DISPLAY 1.021277 (-700 6950);
FORCEPROP 1 LAST TOLERANCE 10%
R 1
J 0
(-900 7000);
DISPLAY 1.212766 (-900 7000);
PAINT GREEN (-900 7000);
DISPLAY INVISIBLE (-900 7000);
FORCEPROP 1 LAST CLS_PN G105-0B104-CK
R 1
J 0
(-900 6950);
DISPLAY 1.212766 (-900 6950);
PAINT GREEN (-900 6950);
DISPLAY INVISIBLE (-900 6950);
FORCEPROP 2 LAST CDS_LIB passive
J 0
(-800 6900);
DISPLAY INVISIBLE (-800 6900);
FORCEPROP 1 LAST CDS_LMAN_SYM_OUTLINE 0,50,50,-50
R 1
J 2
(-800 6900);
DISPLAY 0.468085 (-800 6900);
PAINT GREEN (-800 6900);
DISPLAY INVISIBLE (-800 6900);
FORCEPROP 1 LAST PATH I43
R 1
J 0
(-900 6950);
DISPLAY 1.212766 (-900 6950);
PAINT GREEN (-900 6950);
DISPLAY INVISIBLE (-900 6950);
FORCEADD CAPACITOR..1
R 3
(-6850 6950);
FORCEPROP 1 LAST $LOCATION C272
J 0
(-6750 6850);
DISPLAY 1.212766 (-6750 6850);
PAINT GREEN (-6750 6850);
FORCEPROP 0 LAST CDS_LOCATION C272
R 1
J 0
(-6750 7050);
DISPLAY 1.021277 (-6750 7050);
DISPLAY INVISIBLE (-6750 7050);
FORCEPROP 0 LAST $SEC 1
R 1
J 0
(-6750 7050);
DISPLAY 0.680851 (-6750 7050);
PAINT MONO (-6750 7050);
DISPLAY INVISIBLE (-6750 7050);
FORCEPROP 0 LAST CDS_SEC 1
R 1
J 0
(-6750 7050);
DISPLAY 1.021277 (-6750 7050);
DISPLAY INVISIBLE (-6750 7050);
FORCEPROP 0 LASTPIN (-6850 7050) $PN 1
R 1
J 0
(-6860 7060);
DISPLAY 0.680851 (-6860 7060);
PAINT MONO (-6860 7060);
FORCEPROP 0 LASTPIN (-6850 6800) $PN 2
R 1
J 2
(-6860 6790);
DISPLAY 0.680851 (-6860 6790);
PAINT MONO (-6860 6790);
FORCEPROP 1 LAST VALUE 0.1UF
J 0
(-6750 6950);
DISPLAY 1.212766 (-6750 6950);
PAINT GREEN (-6750 6950);
FORCEPROP 0 LAST PACKAGE 0402
J 0
(-6750 6800);
DISPLAY 1.021277 (-6750 6800);
FORCEPROP 0 LAST VOLTAGE 25V
J 0
(-6750 7050);
DISPLAY 1.021277 (-6750 7050);
FORCEPROP 1 LAST PATH I44
R 1
J 0
(-6950 7000);
DISPLAY 1.212766 (-6950 7000);
PAINT GREEN (-6950 7000);
DISPLAY INVISIBLE (-6950 7000);
FORCEPROP 2 LAST CDS_LIB passive
J 0
(-6850 6950);
DISPLAY INVISIBLE (-6850 6950);
FORCEPROP 1 LAST CDS_LMAN_SYM_OUTLINE 0,50,50,-50
R 1
J 2
(-6850 6950);
DISPLAY 0.468085 (-6850 6950);
PAINT GREEN (-6850 6950);
DISPLAY INVISIBLE (-6850 6950);
FORCEPROP 1 LAST TOLERANCE 10%
R 1
J 0
(-6950 7050);
DISPLAY 1.212766 (-6950 7050);
PAINT GREEN (-6950 7050);
DISPLAY INVISIBLE (-6950 7050);
FORCEPROP 1 LAST CLS_PN G105-0B104-EK
R 1
J 0
(-6950 7000);
DISPLAY 1.212766 (-6950 7000);
PAINT GREEN (-6950 7000);
DISPLAY INVISIBLE (-6950 7000);
FORCEADD CAPACITOR..1
R 3
(-2600 6850);
FORCEPROP 1 LAST $LOCATION C273
J 0
(-2500 6750);
DISPLAY 1.212766 (-2500 6750);
PAINT GREEN (-2500 6750);
FORCEPROP 0 LAST CDS_LOCATION C273
R 1
J 0
(-2500 6950);
DISPLAY 1.021277 (-2500 6950);
DISPLAY INVISIBLE (-2500 6950);
FORCEPROP 0 LAST $SEC 1
R 1
J 0
(-2500 6950);
DISPLAY 0.680851 (-2500 6950);
PAINT MONO (-2500 6950);
DISPLAY INVISIBLE (-2500 6950);
FORCEPROP 0 LAST CDS_SEC 1
R 1
J 0
(-2500 6950);
DISPLAY 1.021277 (-2500 6950);
DISPLAY INVISIBLE (-2500 6950);
FORCEPROP 0 LASTPIN (-2600 6950) $PN 1
R 1
J 0
(-2610 6960);
DISPLAY 0.680851 (-2610 6960);
PAINT MONO (-2610 6960);
FORCEPROP 0 LASTPIN (-2600 6700) $PN 2
R 1
J 2
(-2610 6690);
DISPLAY 0.680851 (-2610 6690);
PAINT MONO (-2610 6690);
FORCEPROP 1 LAST VALUE 0.1UF
J 0
(-2500 6850);
DISPLAY 1.212766 (-2500 6850);
PAINT GREEN (-2500 6850);
FORCEPROP 0 LAST VOLTAGE 10V
J 0
(-2500 6950);
DISPLAY 1.021277 (-2500 6950);
FORCEPROP 0 LAST PACKAGE 0402
J 0
(-2500 7000);
DISPLAY 1.021277 (-2500 7000);
FORCEPROP 1 LAST TOLERANCE 10%
R 1
J 0
(-2700 6950);
DISPLAY 1.212766 (-2700 6950);
PAINT GREEN (-2700 6950);
DISPLAY INVISIBLE (-2700 6950);
FORCEPROP 2 LAST CDS_LIB passive
J 0
(-2600 6850);
DISPLAY INVISIBLE (-2600 6850);
FORCEPROP 1 LAST CDS_LMAN_SYM_OUTLINE 0,50,50,-50
R 1
J 2
(-2600 6850);
DISPLAY 0.468085 (-2600 6850);
PAINT GREEN (-2600 6850);
DISPLAY INVISIBLE (-2600 6850);
FORCEPROP 1 LAST CLS_PN G105-0B104-CK
R 1
J 0
(-2700 6900);
DISPLAY 1.212766 (-2700 6900);
PAINT GREEN (-2700 6900);
DISPLAY INVISIBLE (-2700 6900);
FORCEPROP 1 LAST PATH I45
R 1
J 0
(-2700 6900);
DISPLAY 1.212766 (-2700 6900);
PAINT GREEN (-2700 6900);
DISPLAY INVISIBLE (-2700 6900);
FORCEADD OFFPAGE_OUT..1
R 2
(-8900 5800);
FORCEPROP 2 LAST PATH I46
J 0
(-8850 5900);
DISPLAY 1.021277 (-8850 5900);
DISPLAY INVISIBLE (-8850 5900);
FORCEPROP 1 LAST OFFPAGE TRUE
J 2
(-8910 5855);
DISPLAY 0.808511 (-8910 5855);
PAINT GREEN (-8910 5855);
DISPLAY INVISIBLE (-8910 5855);
FORCEPROP 2 LAST CDS_LIB cls
J 0
(-8900 5800);
DISPLAY INVISIBLE (-8900 5800);
FORCEPROP 1 LAST CDS_LMAN_SYM_OUTLINE -50,50,50,-50
J 2
(-8900 5800);
DISPLAY 0.468085 (-8900 5800);
PAINT GREEN (-8900 5800);
DISPLAY INVISIBLE (-8900 5800);
FORCEPROP 1 LAST BODY_TYPE COMMENT
J 2
(-8910 5935);
DISPLAY 0.808511 (-8910 5935);
PAINT GREEN (-8910 5935);
DISPLAY INVISIBLE (-8910 5935);
FORCEPROP 2 LAST $XR0 24F15< 
J 0
(-9114 5800);
DISPLAY 0.638298 (-9114 5800);
PAINT MONO (-9114 5800);
FORCEADD OFFPAGE_IN..2
R 2
(-8900 5700);
FORCEPROP 2 LAST PATH I47
J 0
(-8850 5800);
DISPLAY 1.021277 (-8850 5800);
DISPLAY INVISIBLE (-8850 5800);
FORCEPROP 1 LAST OFFPAGE TRUE
J 2
(-8910 5755);
DISPLAY 0.808511 (-8910 5755);
PAINT GREEN (-8910 5755);
DISPLAY INVISIBLE (-8910 5755);
FORCEPROP 2 LAST CDS_LIB cls
J 0
(-8900 5700);
DISPLAY INVISIBLE (-8900 5700);
FORCEPROP 1 LAST CDS_LMAN_SYM_OUTLINE -50,50,50,-50
J 2
(-8900 5700);
DISPLAY 0.468085 (-8900 5700);
PAINT GREEN (-8900 5700);
DISPLAY INVISIBLE (-8900 5700);
FORCEPROP 1 LAST BODY_TYPE COMMENT
J 2
(-8910 5835);
DISPLAY 0.808511 (-8910 5835);
PAINT GREEN (-8910 5835);
DISPLAY INVISIBLE (-8910 5835);
FORCEPROP 2 LAST $XR0 24E15> 
J 0
(-9114 5700);
DISPLAY 0.638298 (-9114 5700);
PAINT MONO (-9114 5700);
FORCEADD RESISTOR..1
(-6300 5950);
FORCEPROP 1 LAST $LOCATION R111
J 2
(-6500 5950);
DISPLAY 1.212766 (-6500 5950);
PAINT GREEN (-6500 5950);
FORCEPROP 0 LAST CDS_LOCATION R111
J 0
(-6100 6050);
DISPLAY 1.021277 (-6100 6050);
DISPLAY INVISIBLE (-6100 6050);
FORCEPROP 0 LAST $SEC 1
J 0
(-6100 6050);
DISPLAY 0.680851 (-6100 6050);
PAINT MONO (-6100 6050);
DISPLAY INVISIBLE (-6100 6050);
FORCEPROP 0 LAST CDS_SEC 1
J 0
(-6100 6050);
DISPLAY 1.021277 (-6100 6050);
DISPLAY INVISIBLE (-6100 6050);
FORCEPROP 0 LASTPIN (-6400 5950) $PN 1
J 2
(-6410 5960);
DISPLAY 0.680851 (-6410 5960);
PAINT MONO (-6410 5960);
FORCEPROP 0 LASTPIN (-6150 5950) $PN 2
J 0
(-6140 5960);
DISPLAY 0.680851 (-6140 5960);
PAINT MONO (-6140 5960);
FORCEPROP 0 LAST PACKAGE 0402
J 0
(-6350 5950);
DISPLAY 0.808511 (-6350 5950);
FORCEPROP 1 LAST VALUE 33OHM
J 0
(-6100 5950);
DISPLAY 1.234043 (-6100 5950);
PAINT GREEN (-6100 5950);
FORCEPROP 1 LAST PATH I5
J 0
(-6497 6055);
DISPLAY 1.212766 (-6497 6055);
PAINT GREEN (-6497 6055);
DISPLAY INVISIBLE (-6497 6055);
FORCEPROP 1 LAST TOLERANCE 1%
J 0
(-6497 6205);
DISPLAY 1.212766 (-6497 6205);
PAINT GREEN (-6497 6205);
DISPLAY INVISIBLE (-6497 6205);
FORCEPROP 1 LAST CLS_PN G155-133R0-01
J 0
(-6436 6150);
DISPLAY 1.212766 (-6436 6150);
PAINT GREEN (-6436 6150);
DISPLAY INVISIBLE (-6436 6150);
FORCEPROP 2 LAST CDS_LIB passive
J 0
(-6300 5950);
DISPLAY INVISIBLE (-6300 5950);
FORCEPROP 1 LAST CDS_LMAN_SYM_OUTLINE -50,50,100,-50
J 0
(-6300 5950);
DISPLAY 0.468085 (-6300 5950);
PAINT GREEN (-6300 5950);
DISPLAY INVISIBLE (-6300 5950);
FORCEPROP 2 LAST SIGNAL_MODEL DEFAULT_RESISTOR_33OHM_2_1
J 0
(-6450 6150);
DISPLAY 1.021277 (-6450 6150);
DISPLAY INVISIBLE (-6450 6150);
FORCEADD VCC..1
(-3850 7400);
FORCEPROP 3 LASTPIN (-3800 7350) SIG_NAME XP3R3V_GPS\g
J 0
(-3790 7360);
DISPLAY 0.659574 (-3790 7360);
PAINT MONO (-3790 7360);
DISPLAY INVISIBLE (-3790 7360);
FORCEPROP 0 LAST VOLTAGE 3.3V
J 0
(-4100 7550);
DISPLAY 1.021277 (-4100 7550);
DISPLAY BOTH (-4100 7550);
FORCEPROP 1 LAST HDL_POWER XP3R3V_GPS
J 1
(-3795 7455);
DISPLAY 1.021277 (-3795 7455);
PAINT GREEN (-3795 7455);
FORCEPROP 1 LAST BODY_TYPE PLUMBING
J 0
(-3895 7357);
DISPLAY 0.340426 (-3895 7357);
PAINT GREEN (-3895 7357);
DISPLAY INVISIBLE (-3895 7357);
FORCEPROP 1 LAST CDS_LMAN_SYM_OUTLINE -250,250,250,-250
J 0
(-3850 7400);
DISPLAY 0.468085 (-3850 7400);
PAINT GREEN (-3850 7400);
DISPLAY INVISIBLE (-3850 7400);
FORCEPROP 1 LAST PATH I54
J 0
(-3815 7490);
DISPLAY 0.808511 (-3815 7490);
PAINT GREEN (-3815 7490);
DISPLAY INVISIBLE (-3815 7490);
FORCEPROP 2 LAST CDS_LIB cls
J 0
(-3850 7400);
DISPLAY INVISIBLE (-3850 7400);
FORCEADD FERRITEBEAD..1
(-1300 7200);
FORCEPROP 1 LAST LOCATION L16
J 2
(-1360 7259);
DISPLAY 1.212766 (-1360 7259);
PAINT GREEN (-1360 7259);
FORCEPROP 0 LAST $SEC 1
J 0
(-1050 7350);
DISPLAY 0.680851 (-1050 7350);
PAINT MONO (-1050 7350);
DISPLAY INVISIBLE (-1050 7350);
FORCEPROP 0 LAST CDS_SEC 1
J 0
(-1050 7350);
DISPLAY 1.021277 (-1050 7350);
DISPLAY INVISIBLE (-1050 7350);
FORCEPROP 0 LASTPIN (-1400 7150) $PN 1
J 2
(-1410 7160);
DISPLAY 0.680851 (-1410 7160);
PAINT MONO (-1410 7160);
FORCEPROP 0 LASTPIN (-1000 7150) $PN 2
J 0
(-990 7160);
DISPLAY 0.680851 (-990 7160);
PAINT MONO (-990 7160);
FORCEPROP 1 LAST VALUE 120OHM
J 0
(-1050 7250);
DISPLAY 1.212766 (-1050 7250);
PAINT GREEN (-1050 7250);
FORCEPROP 0 LAST PACKAGE 0603
J 0
(-1300 7250);
DISPLAY 1.021277 (-1300 7250);
FORCEPROP 1 LAST CLS_PN G191-10100-01
J 2
(-1350 7250);
DISPLAY 1.212766 (-1350 7250);
PAINT GREEN (-1350 7250);
DISPLAY INVISIBLE (-1350 7250);
FORCEPROP 1 LAST TOLERANCE 25%
J 0
(-1400 7250);
DISPLAY 1.212766 (-1400 7250);
PAINT GREEN (-1400 7250);
DISPLAY INVISIBLE (-1400 7250);
FORCEPROP 1 LAST PATH I55
J 2
(-1350 7250);
DISPLAY 1.212766 (-1350 7250);
PAINT GREEN (-1350 7250);
DISPLAY INVISIBLE (-1350 7250);
FORCEPROP 1 LAST CDS_LMAN_SYM_OUTLINE 0,0,200,-100
J 0
(-1300 7200);
DISPLAY 0.468085 (-1300 7200);
PAINT GREEN (-1300 7200);
DISPLAY INVISIBLE (-1300 7200);
FORCEPROP 2 LAST CDS_LIB passive
J 0
(-1300 7200);
DISPLAY INVISIBLE (-1300 7200);
FORCEADD FERRITEBEAD..1
(-6550 7300);
FORCEPROP 1 LAST LOCATION L15
J 2
(-6610 7359);
DISPLAY 1.212766 (-6610 7359);
PAINT GREEN (-6610 7359);
FORCEPROP 0 LAST $SEC 1
J 0
(-6300 7450);
DISPLAY 0.680851 (-6300 7450);
PAINT MONO (-6300 7450);
DISPLAY INVISIBLE (-6300 7450);
FORCEPROP 0 LAST CDS_SEC 1
J 0
(-6300 7450);
DISPLAY 1.021277 (-6300 7450);
DISPLAY INVISIBLE (-6300 7450);
FORCEPROP 0 LASTPIN (-6650 7250) $PN 1
J 2
(-6660 7260);
DISPLAY 0.680851 (-6660 7260);
PAINT MONO (-6660 7260);
FORCEPROP 0 LASTPIN (-6250 7250) $PN 2
J 0
(-6240 7260);
DISPLAY 0.680851 (-6240 7260);
PAINT MONO (-6240 7260);
FORCEPROP 0 LAST PACKAGE 0603
J 0
(-6550 7350);
DISPLAY 1.021277 (-6550 7350);
FORCEPROP 1 LAST VALUE 120OHM
J 0
(-6300 7350);
DISPLAY 1.212766 (-6300 7350);
PAINT GREEN (-6300 7350);
FORCEPROP 1 LAST TOLERANCE 25%
J 0
(-6650 7350);
DISPLAY 1.212766 (-6650 7350);
PAINT GREEN (-6650 7350);
DISPLAY INVISIBLE (-6650 7350);
FORCEPROP 1 LAST CLS_PN G191-10100-01
J 2
(-6600 7350);
DISPLAY 1.212766 (-6600 7350);
PAINT GREEN (-6600 7350);
DISPLAY INVISIBLE (-6600 7350);
FORCEPROP 1 LAST CDS_LMAN_SYM_OUTLINE 0,0,200,-100
J 0
(-6550 7300);
DISPLAY 0.468085 (-6550 7300);
PAINT GREEN (-6550 7300);
DISPLAY INVISIBLE (-6550 7300);
FORCEPROP 1 LAST PATH I56
J 2
(-6600 7350);
DISPLAY 1.212766 (-6600 7350);
PAINT GREEN (-6600 7350);
DISPLAY INVISIBLE (-6600 7350);
FORCEPROP 2 LAST CDS_LIB passive
J 0
(-6550 7300);
DISPLAY INVISIBLE (-6550 7300);
FORCEADD OFFPAGE_IN..2
(-3250 6300);
FORCEPROP 2 LAST CDS_LIB cls
J 0
(-3250 6300);
DISPLAY INVISIBLE (-3250 6300);
FORCEPROP 2 LAST PATH I57
J 0
(-3200 6400);
DISPLAY 1.021277 (-3200 6400);
DISPLAY INVISIBLE (-3200 6400);
FORCEPROP 1 LAST CDS_LMAN_SYM_OUTLINE -50,50,50,-50
J 0
(-3250 6300);
DISPLAY 0.468085 (-3250 6300);
PAINT GREEN (-3250 6300);
DISPLAY INVISIBLE (-3250 6300);
FORCEPROP 1 LAST OFFPAGE TRUE
J 0
(-3240 6355);
DISPLAY 0.808511 (-3240 6355);
PAINT GREEN (-3240 6355);
DISPLAY INVISIBLE (-3240 6355);
FORCEPROP 1 LAST BODY_TYPE COMMENT
J 0
(-3240 6435);
DISPLAY 0.808511 (-3240 6435);
PAINT GREEN (-3240 6435);
DISPLAY INVISIBLE (-3240 6435);
FORCEPROP 2 LAST $XR0 25C6<> 
J 0
(-3195 6300);
DISPLAY 0.638298 (-3195 6300);
PAINT MONO (-3195 6300);
FORCEADD RESISTOR..1
(-6300 5700);
FORCEPROP 1 LAST $LOCATION R113
J 2
(-6500 5700);
DISPLAY 1.212766 (-6500 5700);
PAINT GREEN (-6500 5700);
FORCEPROP 0 LAST CDS_LOCATION R113
J 0
(-6100 5800);
DISPLAY 1.021277 (-6100 5800);
DISPLAY INVISIBLE (-6100 5800);
FORCEPROP 0 LAST $SEC 1
J 0
(-6100 5800);
DISPLAY 0.680851 (-6100 5800);
PAINT MONO (-6100 5800);
DISPLAY INVISIBLE (-6100 5800);
FORCEPROP 0 LAST CDS_SEC 1
J 0
(-6100 5800);
DISPLAY 1.021277 (-6100 5800);
DISPLAY INVISIBLE (-6100 5800);
FORCEPROP 0 LASTPIN (-6400 5700) $PN 1
J 2
(-6410 5710);
DISPLAY 0.680851 (-6410 5710);
PAINT MONO (-6410 5710);
FORCEPROP 0 LASTPIN (-6150 5700) $PN 2
J 0
(-6140 5710);
DISPLAY 0.680851 (-6140 5710);
PAINT MONO (-6140 5710);
FORCEPROP 1 LAST VALUE 33OHM
J 0
(-6100 5700);
DISPLAY 1.234043 (-6100 5700);
PAINT GREEN (-6100 5700);
FORCEPROP 0 LAST PACKAGE 0402
J 0
(-6350 5700);
DISPLAY 0.808511 (-6350 5700);
FORCEPROP 1 LAST PATH I7
J 0
(-6497 5805);
DISPLAY 1.212766 (-6497 5805);
PAINT GREEN (-6497 5805);
DISPLAY INVISIBLE (-6497 5805);
FORCEPROP 1 LAST TOLERANCE 1%
J 0
(-6497 5955);
DISPLAY 1.212766 (-6497 5955);
PAINT GREEN (-6497 5955);
DISPLAY INVISIBLE (-6497 5955);
FORCEPROP 1 LAST CLS_PN G155-133R0-01
J 0
(-6436 5900);
DISPLAY 1.212766 (-6436 5900);
PAINT GREEN (-6436 5900);
DISPLAY INVISIBLE (-6436 5900);
FORCEPROP 2 LAST SIGNAL_MODEL DEFAULT_RESISTOR_33OHM_2_1
J 0
(-6450 5900);
DISPLAY 1.021277 (-6450 5900);
DISPLAY INVISIBLE (-6450 5900);
FORCEPROP 1 LAST CDS_LMAN_SYM_OUTLINE -50,50,100,-50
J 0
(-6300 5700);
DISPLAY 0.468085 (-6300 5700);
PAINT GREEN (-6300 5700);
DISPLAY INVISIBLE (-6300 5700);
FORCEPROP 2 LAST CDS_LIB passive
J 0
(-6300 5700);
DISPLAY INVISIBLE (-6300 5700);
FORCEADD RESISTOR..1
(-6300 5800);
FORCEPROP 1 LAST $LOCATION R112
J 2
(-6500 5800);
DISPLAY 1.212766 (-6500 5800);
PAINT GREEN (-6500 5800);
FORCEPROP 0 LAST CDS_LOCATION R112
J 0
(-6100 5900);
DISPLAY 1.021277 (-6100 5900);
DISPLAY INVISIBLE (-6100 5900);
FORCEPROP 0 LAST $SEC 1
J 0
(-6100 5900);
DISPLAY 0.680851 (-6100 5900);
PAINT MONO (-6100 5900);
DISPLAY INVISIBLE (-6100 5900);
FORCEPROP 0 LAST CDS_SEC 1
J 0
(-6100 5900);
DISPLAY 1.021277 (-6100 5900);
DISPLAY INVISIBLE (-6100 5900);
FORCEPROP 0 LASTPIN (-6400 5800) $PN 1
J 2
(-6410 5810);
DISPLAY 0.680851 (-6410 5810);
PAINT MONO (-6410 5810);
FORCEPROP 0 LASTPIN (-6150 5800) $PN 2
J 0
(-6140 5810);
DISPLAY 0.680851 (-6140 5810);
PAINT MONO (-6140 5810);
FORCEPROP 0 LAST PACKAGE 0402
J 0
(-6350 5800);
DISPLAY 0.808511 (-6350 5800);
FORCEPROP 1 LAST VALUE 33OHM
J 0
(-6100 5800);
DISPLAY 1.234043 (-6100 5800);
PAINT GREEN (-6100 5800);
FORCEPROP 1 LAST PATH I8
J 0
(-6497 5905);
DISPLAY 1.212766 (-6497 5905);
PAINT GREEN (-6497 5905);
DISPLAY INVISIBLE (-6497 5905);
FORCEPROP 1 LAST TOLERANCE 1%
J 0
(-6497 6055);
DISPLAY 1.212766 (-6497 6055);
PAINT GREEN (-6497 6055);
DISPLAY INVISIBLE (-6497 6055);
FORCEPROP 1 LAST CLS_PN G155-133R0-01
J 0
(-6436 6000);
DISPLAY 1.212766 (-6436 6000);
PAINT GREEN (-6436 6000);
DISPLAY INVISIBLE (-6436 6000);
FORCEPROP 2 LAST SIGNAL_MODEL DEFAULT_RESISTOR_33OHM_2_1
J 0
(-6450 6000);
DISPLAY 1.021277 (-6450 6000);
DISPLAY INVISIBLE (-6450 6000);
FORCEPROP 1 LAST CDS_LMAN_SYM_OUTLINE -50,50,100,-50
J 0
(-6300 5800);
DISPLAY 0.468085 (-6300 5800);
PAINT GREEN (-6300 5800);
DISPLAY INVISIBLE (-6300 5800);
FORCEPROP 2 LAST CDS_LIB passive
J 0
(-6300 5800);
DISPLAY INVISIBLE (-6300 5800);
FORCEADD OFFPAGE_IN..2
R 2
(-8900 6050);
FORCEPROP 2 LAST PATH I9
J 0
(-9050 6100);
DISPLAY 1.021277 (-9050 6100);
DISPLAY INVISIBLE (-9050 6100);
FORCEPROP 1 LAST OFFPAGE TRUE
J 2
(-8910 6105);
DISPLAY 0.808511 (-8910 6105);
PAINT GREEN (-8910 6105);
DISPLAY INVISIBLE (-8910 6105);
FORCEPROP 1 LAST CDS_LMAN_SYM_OUTLINE -50,50,50,-50
J 2
(-8900 6050);
DISPLAY 0.468085 (-8900 6050);
PAINT GREEN (-8900 6050);
DISPLAY INVISIBLE (-8900 6050);
FORCEPROP 2 LAST CDS_LIB cls
J 2
(-8900 6050);
DISPLAY INVISIBLE (-8900 6050);
FORCEPROP 1 LAST BODY_TYPE COMMENT
J 2
(-8910 6185);
DISPLAY 0.808511 (-8910 6185);
PAINT GREEN (-8910 6185);
DISPLAY INVISIBLE (-8910 6185);
FORCEPROP 2 LAST $XR0 11C13> 
J 0
(-9114 6050);
DISPLAY 0.638298 (-9114 6050);
PAINT MONO (-9114 6050);
FORCEADD SHEET_A1..1
(3700 -200);
FORCEPROP 2 LAST CUSTOM_TXT_CDS <XR_PAGE_TITLE>
J 0
(-11870 11150);
DISPLAY 0.638298 (-11870 11150);
PAINT PINK (-11870 11150);
FORCEPROP 1 LAST CUSTOM_TXT_CDS <DOCNO>
J 0
(1650 185);
DISPLAY 0.978723 (1650 185);
FORCEPROP 1 LAST CUSTOM_TXT_CDS <CON_PAGE_NUM>
J 0
(1545 -150);
DISPLAY 0.978723 (1545 -150);
FORCEPROP 1 LAST CUSTOM_TXT_CDS <DATE>
J 0
(3000 -25);
DISPLAY 0.978723 (3000 -25);
FORCEPROP 1 LAST CUSTOM_TXT_CDS <TITLE>
J 1
(1915 430);
DISPLAY 0.978723 (1915 430);
FORCEPROP 1 LAST CUSTOM_TXT_CDS <DESIGNER>
J 0
(3000 400);
DISPLAY 0.978723 (3000 400);
FORCEPROP 1 LAST CUSTOM_TXT_CDS <CON_TOTAL_PAGES>
J 0
(1855 -150);
DISPLAY 0.808511 (1855 -150);
FORCEPROP 1 LAST CUSTOM_TXT_CDS <ASSY_PN>
J 0
(1650 -25);
DISPLAY 0.978723 (1650 -25);
FORCEPROP 1 LAST CUSTOM_TXT_CDS <DOCREV>
J 0
(3000 175);
DISPLAY 0.978723 (3000 175);
FORCEPROP 1 LAST TITLE GPS_MODULE_CONN
J 0
(1200 650);
DISPLAY 3.042553 (1200 650);
PAINT GREEN (1200 650);
FORCEPROP 2 LAST PAGE_BORDER TRUE
J 0
(-11870 11150);
DISPLAY 0.638298 (-11870 11150);
PAINT PINK (-11870 11150);
DISPLAY INVISIBLE (-11870 11150);
FORCEPROP 1 LAST CDS_LMAN_SYM_OUTLINE -15850,11500,200,-200
J 0
(3700 -200);
DISPLAY 0.468085 (3700 -200);
PAINT GREEN (3700 -200);
DISPLAY INVISIBLE (3700 -200);
FORCEPROP 2 LAST CDS_LIB cls
J 0
(3700 -200);
DISPLAY INVISIBLE (3700 -200);
FORCEPROP 1 LAST COMMENT_BODY TRUE
J 0
(3710 -145);
DISPLAY 0.808511 (3710 -145);
DISPLAY INVISIBLE (3710 -145);
FORCEPROP 2 LAST CDS_XR_PAGE_TITLE CR-22 : @TIMECARD_LIB.TIMECARD(SCH_1):PAGE22
J 0
(-11870 11150);
DISPLAY 0.638298 (-11870 11150);
PAINT PINK (-11870 11150);
DISPLAY INVISIBLE (-11870 11150);
WIRE 16 -1 (-6250 7250)(-6050 7250);
WIRE 16 -1 (-6050 7250)(-5650 7250);
WIRE 16 -1 (-6050 7050)(-6050 7250);
WIRE 16 -1 (-5650 7250)(-5200 7250);
WIRE 16 -1 (-5650 7250)(-5650 7050);
WIRE 16 -1 (-5200 7050)(-5200 7250);
WIRE 16 -1 (-4750 7250)(-5200 7250);
WIRE 16 -1 (-4750 7250)(-4750 7350);
WIRE 16 -1 (-4750 6250)(-4750 7250);
WIRE 16 -1 (-4550 6250)(-4750 6250);
WIRE 16 -1 (-4050 5950)(-3800 5950);
WIRE 16 -1 (-3800 5500)(-3800 5950);
WIRE 16 -1 (-3450 5500)(-3800 5500);
WIRE 16 -1 (-3800 5500)(-3800 5450);
WIRE 16 -1 (-3450 5500)(-3450 5650);
WIRE 16 -1 (-4750 6050)(-4750 5700);
WIRE 16 -1 (-4550 6050)(-4750 6050);
WIRE 16 -1 (-5750 6050)(-4750 6050);
FORCEPROP 2 LAST SIG_NAME GPS_UART_RXD
J 0
(-5560 6060);
DISPLAY 1.021277 (-5560 6060);
WIRE 16 -1 (-4750 5700)(-6150 5700);
WIRE 16 -1 (-6150 6050)(-5750 6050);
WIRE 16 -1 (-5750 6400)(-5750 6050);
WIRE 16 -1 (-7200 6400)(-5750 6400);
WIRE 16 -1 (-4800 6150)(-4800 5800);
WIRE 16 -1 (-6150 6150)(-4800 6150);
FORCEPROP 2 LAST SIG_NAME GPS_UART_TXD
J 0
(-5560 6160);
DISPLAY 1.021277 (-5560 6160);
WIRE 16 -1 (-4550 6150)(-4800 6150);
WIRE 16 -1 (-4800 5800)(-6150 5800);
WIRE 16 -1 (-4050 6050)(-2150 6050);
FORCEPROP 2 LAST SIG_NAME GPSTP1_OUT
J 0
(-3160 6060);
DISPLAY 1.021277 (-3160 6060);
WIRE 16 -1 (-3450 5900)(-3450 6150);
WIRE 16 -1 (-3400 6150)(-3450 6150);
WIRE 16 -1 (-4050 6150)(-3450 6150);
WIRE 16 -1 (-2150 6150)(-3400 6150);
FORCEPROP 2 LAST SIG_NAME GPS_RST_N
J 0
(-3160 6160);
DISPLAY 1.021277 (-3160 6160);
WIRE 16 -1 (-3400 6300)(-3400 6150);
WIRE 16 -1 (-3400 6300)(-3300 6300);
WIRE 16 -1 (-3400 6600)(-3400 6300);
WIRE 16 -1 (-1900 6150)(-400 6150);
FORCEPROP 2 LAST SIG_NAME FPGA_OUT_GPS_RST_N
J 0
(-1310 6160);
DISPLAY 1.021277 (-1310 6160);
WIRE 16 -1 (-1900 6050)(-400 6050);
FORCEPROP 2 LAST SIG_NAME FPGA_IN_GPSTP1_OUT
J 0
(-1310 6060);
DISPLAY 1.021277 (-1310 6060);
WIRE 16 -1 (-6150 5950)(-4550 5950);
FORCEPROP 2 LAST SIG_NAME GPSTP2_OUT
J 0
(-5560 5960);
DISPLAY 1.021277 (-5560 5960);
WIRE 16 -1 (-6400 5700)(-8850 5700);
FORCEPROP 2 LAST SIG_NAME DBG_UART_GPS_RXD
J 0
(-8810 5710);
DISPLAY 1.021277 (-8810 5710);
WIRE 16 -1 (-6400 5800)(-8850 5800);
FORCEPROP 2 LAST SIG_NAME DBG_UART_GPS_TXD
J 0
(-8810 5810);
DISPLAY 1.021277 (-8810 5810);
WIRE 16 -1 (-8850 5950)(-6400 5950);
FORCEPROP 2 LAST SIG_NAME FPGA_IN_GPSTP2_OUT
J 0
(-8810 5960);
DISPLAY 1.021277 (-8810 5960);
WIRE 16 -1 (-6400 6050)(-8850 6050);
FORCEPROP 2 LAST SIG_NAME UART_GPS_RX_FPGA_TX
J 0
(-8810 6060);
DISPLAY 1.021277 (-8810 6060);
WIRE 16 -1 (-7450 6400)(-7850 6400);
WIRE 16 -1 (-7850 6300)(-7850 6400);
WIRE 16 -1 (-7850 6400)(-7850 6550);
WIRE 16 -1 (-7450 6300)(-7850 6300);
WIRE 16 -1 (-7200 6300)(-6800 6300);
WIRE 16 -1 (-6800 6300)(-6800 6150);
WIRE 16 -1 (-6400 6150)(-6800 6150);
WIRE 16 -1 (-8850 6150)(-6800 6150);
FORCEPROP 2 LAST SIG_NAME UART_GPS_TX_FPGA_RX
J 0
(-8810 6160);
DISPLAY 1.021277 (-8810 6160);
WIRE 16 -1 (-7050 7350)(-7050 7250);
WIRE 16 -1 (-7050 7250)(-6850 7250);
WIRE 16 -1 (-6650 7250)(-6850 7250);
WIRE 16 -1 (-6850 7250)(-6850 7050);
WIRE 16 -1 (-5200 6700)(-5200 6800);
WIRE 16 -1 (-5200 6700)(-5200 6650);
WIRE 16 -1 (-5200 6700)(-5650 6700);
WIRE 16 -1 (-5650 6700)(-5650 6800);
WIRE 16 -1 (-5650 6700)(-6050 6700);
WIRE 16 -1 (-6050 6800)(-6050 6700);
WIRE 16 -1 (-6850 6700)(-6050 6700);
WIRE 16 -1 (-6850 6800)(-6850 6700);
WIRE 16 -1 (-1600 6950)(-1600 7150);
WIRE 16 -1 (-1600 7150)(-1400 7150);
WIRE 16 -1 (-2150 7150)(-1600 7150);
WIRE 16 -1 (-2150 7150)(-2150 6950);
WIRE 16 -1 (-2600 7150)(-2150 7150);
WIRE 16 -1 (-2600 6950)(-2600 7150);
WIRE 16 -1 (-3400 7150)(-2600 7150);
WIRE 16 -1 (-3400 6850)(-3400 7150);
WIRE 16 -1 (-3400 7150)(-3800 7150);
WIRE 16 -1 (-3800 7350)(-3800 7150);
WIRE 16 -1 (-3800 6250)(-3800 7150);
WIRE 16 -1 (-4050 6250)(-3800 6250);
WIRE 16 -1 (-2150 6550)(-2600 6550);
WIRE 16 -1 (-2150 6550)(-1600 6550);
WIRE 16 -1 (-2150 6550)(-2150 6700);
WIRE 16 -1 (-2600 6700)(-2600 6550);
WIRE 16 -1 (-2600 6550)(-2600 6500);
WIRE 16 -1 (-1600 6550)(-800 6550);
WIRE 16 -1 (-1600 6700)(-1600 6550);
WIRE 16 -1 (-800 6550)(-800 6750);
WIRE 16 -1 (-800 7000)(-800 7150);
WIRE 16 -1 (-450 7150)(-800 7150);
WIRE 16 -1 (-800 7150)(-1000 7150);
WIRE 16 -1 (-450 7150)(-450 7300);
DOT 1 (-3400 6300);
DOT 1 (-800 7150);
DOT 1 (-1600 7150);
DOT 1 (-2150 7150);
DOT 1 (-1600 6550);
DOT 1 (-2150 6550);
DOT 1 (-2600 7150);
DOT 1 (-2600 6550);
DOT 1 (-3400 7150);
DOT 1 (-3800 7150);
DOT 1 (-3450 6150);
DOT 1 (-3400 6150);
DOT 1 (-3800 5500);
DOT 1 (-4750 7250);
DOT 1 (-5200 7250);
DOT 1 (-4750 6050);
DOT 1 (-4800 6150);
DOT 1 (-5200 6700);
DOT 1 (-5650 7250);
DOT 1 (-6050 7250);
DOT 1 (-5650 6700);
DOT 1 (-5750 6050);
DOT 1 (-6050 6700);
DOT 1 (-6850 7250);
DOT 1 (-6800 6150);
DOT 1 (-7850 6400);
FORCENOTE
GPS_MODULE_CONN
(-5800 9500) 0;
DISPLAY LEFT (-5800 9500);
DISPLAY 4.914894 (-5800 9500);
QUIT
